# T6G (Grand Teton) — schematic netlist excerpt (pin names and nets, part order shuffled) for the footprints in the layout excerpt that follows; sources: Cadence DE-HDL packaged netlist, KiCad conversion of 04192023_DAF0TMB3IC0_F0TG_MB_C_brd_V02_OCP.brd

PC116_3  Q_CAP  0.1UF 25V 10% X7R  pkg 0402  page 202 : A = SW_P12V_AUX_PVDDCR_CPU1_P0_FLT ; B = GND
PC317  Q_CAP  560PF 50V 10% EMPTY  pkg C0402  page 212 : A = SW_PVDDCR_CPU0_P1_SW4 ; B = SW_PVDDCR_CPU0_P1_SW4_RC

(kicad_pcb
	(version 20260206)
	(generator "pcbnew")
	(generator_version "10.0")
	(general
		(thickness 1.6)
		(legacy_teardrops no)
	)
	(paper "A4")
	(title_block
		(title "04192023_DAF0TMB3IC0_F0TG_MB_C_brd_V02_OCP.brd")
		(comment 1 "Grand Teton / footprints 2161-2162 of 8354")
	)
	(layers
		(0 "F.Cu" signal "TOP")
		(4 "In1.Cu" signal "GND")
		(6 "In2.Cu" signal "IN1")
		(8 "In3.Cu" signal "GND1")
		(10 "In4.Cu" signal "IN2")
		(12 "In5.Cu" signal "GND2")
		(14 "In6.Cu" signal "IN3")
		(16 "In7.Cu" signal "GND3")
		(18 "In8.Cu" signal "VCC")
		(20 "In9.Cu" signal "VCC1")
		(22 "In10.Cu" signal "GND4")
		(24 "In11.Cu" signal "IN4")
		(26 "In12.Cu" signal "GND5")
		(28 "In13.Cu" signal "IN5")
		(30 "In14.Cu" signal "GND6")
		(32 "In15.Cu" signal "IN6")
		(34 "In16.Cu" signal "GND7")
		(2 "B.Cu" signal "BOTTOM")
		(9 "F.Adhes" user "F.Adhesive")
		(11 "B.Adhes" user "B.Adhesive")
		(13 "F.Paste" user "Package Geometry/Pastemask Top")
		(15 "B.Paste" user "Package Geometry/Pastemask Bottom")
		(5 "F.SilkS" user "Ref Des/Silkscreen Top")
		(7 "B.SilkS" user "Ref Des/Silkscreen Bottom")
		(1 "F.Mask" user "Board Geometry/Soldermask Top")
		(3 "B.Mask" user "Board Geometry/Soldermask Bottom")
		(17 "Dwgs.User" user "User.Drawings")
		(19 "Cmts.User" user "User.Comments")
		(21 "Eco1.User" user "User.Eco1")
		(23 "Eco2.User" user "User.Eco2")
		(25 "Edge.Cuts" user "Board Geometry/Outline")
		(27 "Margin" user)
		(31 "F.CrtYd" user "Package Geometry/Place Bound Top")
		(29 "B.CrtYd" user "Package Geometry/Place Bound Bottom")
		(35 "F.Fab" user "Ref Des/Assembly Top")
		(33 "B.Fab" user "Ref Des/Assembly Bottom")
	)
	(footprint ""
		(layer "F.Cu")
		(at 320.572384 -341.042244 180)
		(property "Reference" "PC116_3"
			(at 0 0 180)
			(layer "F.SilkS")
			(hide yes)
			(effects
				(font
					(size 1.27 1.27)
				)
			)
		)
		(property "Value" ""
			(at 0 0 180)
			(layer "F.Fab")
			(effects
				(font
					(size 1.27 1.27)
				)
			)
		)
		(duplicate_pad_numbers_are_jumpers no)
		(fp_line
			(start 0.7874 0.4064)
			(end -0.7874 0.4064)
			(stroke
				(width 0.1524)
				(type default)
			)
			(layer "F.SilkS")
		)
		(fp_line
			(start 0.7874 -0.4064)
			(end 0.7874 0.4064)
			(stroke
				(width 0.1524)
				(type default)
			)
			(layer "F.SilkS")
		)
		(fp_line
			(start -0.7874 0.4064)
			(end -0.7874 -0.4064)
			(stroke
				(width 0.1524)
				(type default)
			)
			(layer "F.SilkS")
		)
		(fp_line
			(start -0.7874 -0.4064)
			(end 0.7874 -0.4064)
			(stroke
				(width 0.1524)
				(type default)
			)
			(layer "F.SilkS")
		)
		(fp_line
			(start 0.67945 0.3048)
			(end 0.120396 0.3048)
			(stroke
				(width 0.1)
				(type default)
			)
			(layer "F.Fab")
		)
		(fp_line
			(start 0.67945 -0.3048)
			(end 0.67945 0.3048)
			(stroke
				(width 0.1)
				(type default)
			)
			(layer "F.Fab")
		)
		(fp_line
			(start 0.12065 -0.2794)
			(end 0.12065 -0.3048)
			(stroke
				(width 0.1)
				(type default)
			)
			(layer "F.Fab")
		)
		(fp_line
			(start 0.12065 -0.3048)
			(end 0.67945 -0.3048)
			(stroke
				(width 0.1)
				(type default)
			)
			(layer "F.Fab")
		)
		(fp_line
			(start 0.120396 0.3048)
			(end 0.120396 0.2794)
			(stroke
				(width 0.1)
				(type default)
			)
			(layer "F.Fab")
		)
		(fp_line
			(start 0.120396 0.2794)
			(end -0.12065 0.2794)
			(stroke
				(width 0.1)
				(type default)
			)
			(layer "F.Fab")
		)
		(fp_line
			(start -0.12065 0.3048)
			(end -0.67945 0.3048)
			(stroke
				(width 0.1)
				(type default)
			)
			(layer "F.Fab")
		)
		(fp_line
			(start -0.12065 0.2794)
			(end -0.12065 0.3048)
			(stroke
				(width 0.1)
				(type default)
			)
			(layer "F.Fab")
		)
		(fp_line
			(start -0.12065 -0.2794)
			(end 0.12065 -0.2794)
			(stroke
				(width 0.1)
				(type default)
			)
			(layer "F.Fab")
		)
		(fp_line
			(start -0.12065 -0.305054)
			(end -0.12065 -0.2794)
			(stroke
				(width 0.1)
				(type default)
			)
			(layer "F.Fab")
		)
		(fp_line
			(start -0.67945 0.3048)
			(end -0.67945 -0.305054)
			(stroke
				(width 0.1)
				(type default)
			)
			(layer "F.Fab")
		)
		(fp_line
			(start -0.67945 -0.305054)
			(end -0.12065 -0.305054)
			(stroke
				(width 0.1)
				(type default)
			)
			(layer "F.Fab")
		)
		(pad "1" smd circle
			(at -0.40005 0 180)
			(size 0 0)
			(layers "F.Cu" "F.Mask" "F.Paste")
			(net "SW_P12V_AUX_PVDDCR_CPU1_P0_FLT")
		)
		(pad "2" smd circle
			(at 0.40005 0 180)
			(size 0 0)
			(layers "F.Cu" "F.Mask" "F.Paste")
			(net "GND")
		)
	)
	(footprint ""
		(layer "F.Cu")
		(at 111.149892 -181.176168)
		(property "Reference" "PC317"
			(at 0 0 0)
			(layer "F.SilkS")
			(hide yes)
			(effects
				(font
					(size 1.27 1.27)
				)
			)
		)
		(property "Value" ""
			(at 0 0 0)
			(layer "F.Fab")
			(effects
				(font
					(size 1.27 1.27)
				)
			)
		)
		(duplicate_pad_numbers_are_jumpers no)
		(fp_line
			(start -0.7874 -0.4064)
			(end 0.7874 -0.4064)
			(stroke
				(width 0.1524)
				(type default)
			)
			(layer "F.SilkS")
		)
		(fp_line
			(start -0.7874 0.4064)
			(end -0.7874 -0.4064)
			(stroke
				(width 0.1524)
				(type default)
			)
			(layer "F.SilkS")
		)
		(fp_line
			(start 0.7874 -0.4064)
			(end 0.7874 0.4064)
			(stroke
				(width 0.1524)
				(type default)
			)
			(layer "F.SilkS")
		)
		(fp_line
			(start 0.7874 0.4064)
			(end -0.7874 0.4064)
			(stroke
				(width 0.1524)
				(type default)
			)
			(layer "F.SilkS")
		)
		(fp_line
			(start -0.67945 -0.305054)
			(end -0.12065 -0.305054)
			(stroke
				(width 0.1)
				(type default)
			)
			(layer "F.Fab")
		)
		(fp_line
			(start -0.67945 0.3048)
			(end -0.67945 -0.305054)
			(stroke
				(width 0.1)
				(type default)
			)
			(layer "F.Fab")
		)
		(fp_line
			(start -0.12065 -0.305054)
			(end -0.12065 -0.2794)
			(stroke
				(width 0.1)
				(type default)
			)
			(layer "F.Fab")
		)
		(fp_line
			(start -0.12065 -0.2794)
			(end 0.12065 -0.2794)
			(stroke
				(width 0.1)
				(type default)
			)
			(layer "F.Fab")
		)
		(fp_line
			(start -0.12065 0.2794)
			(end -0.12065 0.3048)
			(stroke
				(width 0.1)
				(type default)
			)
			(layer "F.Fab")
		)
		(fp_line
			(start -0.12065 0.3048)
			(end -0.67945 0.3048)
			(stroke
				(width 0.1)
				(type default)
			)
			(layer "F.Fab")
		)
		(fp_line
			(start 0.120396 0.2794)
			(end -0.12065 0.2794)
			(stroke
				(width 0.1)
				(type default)
			)
			(layer "F.Fab")
		)
		(fp_line
			(start 0.120396 0.3048)
			(end 0.120396 0.2794)
			(stroke
				(width 0.1)
				(type default)
			)
			(layer "F.Fab")
		)
		(fp_line
			(start 0.12065 -0.3048)
			(end 0.67945 -0.3048)
			(stroke
				(width 0.1)
				(type default)
			)
			(layer "F.Fab")
		)
		(fp_line
			(start 0.12065 -0.2794)
			(end 0.12065 -0.3048)
			(stroke
				(width 0.1)
				(type default)
			)
			(layer "F.Fab")
		)
		(fp_line
			(start 0.67945 -0.3048)
			(end 0.67945 0.3048)
			(stroke
				(width 0.1)
				(type default)
			)
			(layer "F.Fab")
		)
		(fp_line
			(start 0.67945 0.3048)
			(end 0.120396 0.3048)
			(stroke
				(width 0.1)
				(type default)
			)
			(layer "F.Fab")
		)
		(pad "1" smd circle
			(at -0.40005 0)
			(size 0 0)
			(layers "F.Cu" "F.Mask" "F.Paste")
			(net "SW_PVDDCR_CPU0_P1_SW4")
		)
		(pad "2" smd circle
			(at 0.40005 0)
			(size 0 0)
			(layers "F.Cu" "F.Mask" "F.Paste")
			(net "SW_PVDDCR_CPU0_P1_SW4_RC")
		)
	)
)
